# TIMECARD (Time Appliance Project (Time Card)) — schematic netlist excerpt (pin names and nets, part order shuffled) for the footprints in the layout excerpt that follows; sources: Cadence DE-HDL packaged netlist, KiCad conversion of R4006-B0001-02_R01.brd

C181  CAPACITOR  22UF 10V 20%  pkg SMC_0805R_H057  page 30 : \1\ = XP3R3V ; \2\ = SG
C132  CAPACITOR  0.1UF 10V 10%  pkg SMC_0402R_H022  page 14 : \1\ = XP3R3V_FPGA ; \2\ = SG

(kicad_pcb
	(version 20260206)
	(generator "pcbnew")
	(generator_version "10.0")
	(general
		(thickness 1.6)
		(legacy_teardrops no)
	)
	(paper "A4")
	(title_block
		(title "timecard-production-celestica-r4006 — R4006-B0001-02_R01.brd")
		(comment 1 "Time Appliance Project (Time Card) / footprints 732-733 of 1113")
	)
	(layers
		(0 "F.Cu" signal "TOP")
		(4 "In1.Cu" signal "L02_GND1")
		(6 "In2.Cu" signal "L03_SIG1")
		(8 "In3.Cu" signal "L04_GND2")
		(10 "In4.Cu" signal "L05_VCC1")
		(12 "In5.Cu" signal "L06_VCC2")
		(14 "In6.Cu" signal "L07_GND3")
		(16 "In7.Cu" signal "L08_SIG2")
		(18 "In8.Cu" signal "L09_GND4")
		(2 "B.Cu" signal "BOTTOM")
		(9 "F.Adhes" user "F.Adhesive")
		(11 "B.Adhes" user "B.Adhesive")
		(13 "F.Paste" user "Package Geometry/Pastemask Top")
		(15 "B.Paste" user "Package Geometry/Pastemask Bottom")
		(5 "F.SilkS" user "Ref Des/Silkscreen Top")
		(7 "B.SilkS" user "Ref Des/Silkscreen Bottom")
		(1 "F.Mask" user "Board Geometry/Soldermask Top")
		(3 "B.Mask" user "Board Geometry/Soldermask Bottom")
		(17 "Dwgs.User" user "User.Drawings")
		(19 "Cmts.User" user "User.Comments")
		(21 "Eco1.User" user "User.Eco1")
		(23 "Eco2.User" user "User.Eco2")
		(25 "Edge.Cuts" user "Board Geometry/Outline")
		(27 "Margin" user)
		(31 "F.CrtYd" user "Package Geometry/Place Bound Top")
		(29 "B.CrtYd" user "Package Geometry/Place Bound Bottom")
		(35 "F.Fab" user "Ref Des/Assembly Top")
		(33 "B.Fab" user "Ref Des/Assembly Bottom")
	)
	(footprint ""
		(layer "B.Cu")
		(at 128.1938 -62.3316 180)
		(property "Reference" "C181"
			(at 0.8128 1.76403 0)
			(unlocked yes)
			(layer "B.SilkS")
			(effects
				(font
					(size 0.7874 0.5842)
					(thickness 0.1524)
				)
				(justify mirror)
			)
		)
		(property "Value" "VAL*"
			(at -0.0762 3.134106 180)
			(unlocked yes)
			(layer "B.Fab")
			(hide yes)
			(effects
				(font
					(size 0.7874 0.5842)
					(thickness 0.1524)
				)
				(justify mirror)
			)
		)
		(property "Tolerance" "TOL*"
			(at -0.0762 4.048506 180)
			(unlocked yes)
			(layer "Cmts.User")
			(hide yes)
			(effects
				(font
					(size 0.7874 0.5842)
					(thickness 0.1524)
				)
				(justify mirror)
			)
		)
		(property "User Part Number" "PARTNUM*"
			(at -0.1016 5.013706 180)
			(unlocked yes)
			(layer "Cmts.User")
			(hide yes)
			(effects
				(font
					(size 0.7874 0.5842)
					(thickness 0.1524)
				)
				(justify mirror)
			)
		)
		(property "Device Type" "CAPACITOR-G107-0F226-CM,22UF,2A"
			(at -0.0508 2.194306 180)
			(unlocked yes)
			(layer "B.Fab")
			(hide yes)
			(effects
				(font
					(size 0.7874 0.5842)
					(thickness 0.1524)
				)
				(justify mirror)
			)
		)
		(duplicate_pad_numbers_are_jumpers no)
		(fp_line
			(start 1.5748 0.9398)
			(end -1.5748 0.9398)
			(stroke
				(width 0.1)
				(type default)
			)
			(layer "B.SilkS")
		)
		(fp_line
			(start 1.5748 -0.9398)
			(end 1.5748 0.9398)
			(stroke
				(width 0.1)
				(type default)
			)
			(layer "B.SilkS")
		)
		(fp_line
			(start -1.5748 0.9398)
			(end -1.5748 -0.9398)
			(stroke
				(width 0.1)
				(type default)
			)
			(layer "B.SilkS")
		)
		(fp_line
			(start -1.5748 -0.9398)
			(end 1.5748 -0.9398)
			(stroke
				(width 0.1)
				(type default)
			)
			(layer "B.SilkS")
		)
		(fp_rect
			(start -1.5748 0.9398)
			(end 1.5748 -0.9398)
			(stroke
				(width 0)
				(type default)
			)
			(fill no)
			(layer "B.CrtYd")
		)
		(fp_line
			(start 1.016 0.635)
			(end -1.016 0.635)
			(stroke
				(width 0.1)
				(type default)
			)
			(layer "B.Fab")
		)
		(fp_line
			(start 1.016 -0.635)
			(end 1.016 0.635)
			(stroke
				(width 0.1)
				(type default)
			)
			(layer "B.Fab")
		)
		(fp_line
			(start -1.016 0.635)
			(end -1.016 -0.635)
			(stroke
				(width 0.1)
				(type default)
			)
			(layer "B.Fab")
		)
		(fp_line
			(start -1.016 -0.635)
			(end 1.016 -0.635)
			(stroke
				(width 0.1)
				(type default)
			)
			(layer "B.Fab")
		)
		(pad "1" smd rect
			(at 0.8382 0)
			(size 0.9652 1.3716)
			(layers "B.Cu" "B.Mask" "B.Paste")
			(net "XP3R3V")
		)
		(pad "2" smd rect
			(at -0.8382 0)
			(size 0.9652 1.3716)
			(layers "B.Cu" "B.Mask" "B.Paste")
			(net "SG")
		)
		(zone
			(layer "B.Cu")
			(hatch none 0.5)
			(connect_pads
				(clearance 0)
			)
			(min_thickness 0.25)
			(keepout
				(tracks allowed)
				(vias not_allowed)
				(pads allowed)
				(copperpour not_allowed)
				(footprints allowed)
			)
			(placement
				(enabled no)
				(sheetname "")
			)
			(fill
				(thermal_gap 0.5)
				(thermal_bridge_width 0.5)
				(island_removal_mode 0)
			)
			(polygon
				(pts
					(xy 128.4224 -62.9666) (xy 127.9652 -62.9666) (xy 127.9652 -61.6966) (xy 128.4224 -61.6966)
				)
			)
		)
	)
	(footprint ""
		(layer "B.Cu")
		(at 112.346994 -48.823118)
		(property "Reference" "C132"
			(at -0.078994 -0.929132 0)
			(unlocked yes)
			(layer "B.SilkS")
			(effects
				(font
					(size 0.635 0.4064)
					(thickness 0.1524)
				)
				(justify mirror)
			)
		)
		(property "Value" "VAL*"
			(at 0 3.718306 0)
			(unlocked yes)
			(layer "B.Fab")
			(hide yes)
			(effects
				(font
					(size 0.7874 0.5842)
					(thickness 0.127)
				)
				(justify mirror)
			)
		)
		(property "Device Type" "CAPACITOR-G105-0B104-CK,0.1UF,A"
			(at 0 1.432306 0)
			(unlocked yes)
			(layer "B.Fab")
			(hide yes)
			(effects
				(font
					(size 0.7874 0.5842)
					(thickness 0.127)
				)
				(justify mirror)
			)
		)
		(property "User Part Number" "PARTNUM*"
			(at 0 2.575306 0)
			(unlocked yes)
			(layer "Cmts.User")
			(hide yes)
			(effects
				(font
					(size 0.7874 0.5842)
					(thickness 0.127)
				)
				(justify mirror)
			)
		)
		(property "Tolerance" "TOL*"
			(at 0 4.861306 0)
			(unlocked yes)
			(layer "Cmts.User")
			(hide yes)
			(effects
				(font
					(size 0.7874 0.5842)
					(thickness 0.127)
				)
				(justify mirror)
			)
		)
		(duplicate_pad_numbers_are_jumpers no)
		(fp_line
			(start -0.970026 -0.4699)
			(end -0.970026 0.4699)
			(stroke
				(width 0.1)
				(type default)
			)
			(layer "B.SilkS")
		)
		(fp_line
			(start -0.970026 0.4699)
			(end 0.970026 0.4699)
			(stroke
				(width 0.1)
				(type default)
			)
			(layer "B.SilkS")
		)
		(fp_line
			(start 0.970026 -0.4699)
			(end -0.970026 -0.4699)
			(stroke
				(width 0.1)
				(type default)
			)
			(layer "B.SilkS")
		)
		(fp_line
			(start 0.970026 0.4699)
			(end 0.970026 -0.4699)
			(stroke
				(width 0.1)
				(type default)
			)
			(layer "B.SilkS")
		)
		(fp_poly
			(pts
				(xy 0.970026 0.4699) (xy -0.970026 0.4699) (xy -0.970026 -0.4699) (xy 0.970026 -0.4699)
			)
			(stroke
				(width 0)
				(type default)
			)
			(fill no)
			(layer "B.CrtYd")
		)
		(fp_line
			(start -0.508 -0.3048)
			(end -0.508 0.3048)
			(stroke
				(width 0.1)
				(type default)
			)
			(layer "B.Fab")
		)
		(fp_line
			(start -0.508 0.3048)
			(end 0.508 0.3048)
			(stroke
				(width 0.1)
				(type default)
			)
			(layer "B.Fab")
		)
		(fp_line
			(start 0.508 -0.3048)
			(end -0.508 -0.3048)
			(stroke
				(width 0.1)
				(type default)
			)
			(layer "B.Fab")
		)
		(fp_line
			(start 0.508 0.3048)
			(end 0.508 -0.3048)
			(stroke
				(width 0.1)
				(type default)
			)
			(layer "B.Fab")
		)
		(pad "1" smd circle
			(at 0.500126 0 180)
			(size 0.635 0.635)
			(layers "B.Cu" "B.Mask" "B.Paste")
			(net "XP3R3V_FPGA")
		)
		(pad "2" smd circle
			(at -0.500126 0 180)
			(size 0.635 0.635)
			(layers "B.Cu" "B.Mask" "B.Paste")
			(net "SG")
		)
	)
)
